(kicad_pcb
	(version 20260206)
	(generator "pcbnew")
	(generator_version "10.0")
	(general
		(thickness 1.6)
		(legacy_teardrops no)
	)
	(paper "A4")
	(title_block
		(title "04192023_DAF0TMB3IC0_F0TG_MB_C_brd_V02_OCP.brd")
		(comment 1 "Grand Teton / footprints 1623-1629 of 8354")
	)
	(layers
		(0 "F.Cu" signal "TOP")
		(4 "In1.Cu" signal "GND")
		(6 "In2.Cu" signal "IN1")
		(8 "In3.Cu" signal "GND1")
		(10 "In4.Cu" signal "IN2")
		(12 "In5.Cu" signal "GND2")
		(14 "In6.Cu" signal "IN3")
		(16 "In7.Cu" signal "GND3")
		(18 "In8.Cu" signal "VCC")
		(20 "In9.Cu" signal "VCC1")
		(22 "In10.Cu" signal "GND4")
		(24 "In11.Cu" signal "IN4")
		(26 "In12.Cu" signal "GND5")
		(28 "In13.Cu" signal "IN5")
		(30 "In14.Cu" signal "GND6")
		(32 "In15.Cu" signal "IN6")
		(34 "In16.Cu" signal "GND7")
		(2 "B.Cu" signal "BOTTOM")
		(9 "F.Adhes" user "F.Adhesive")
		(11 "B.Adhes" user "B.Adhesive")
		(13 "F.Paste" user "Package Geometry/Pastemask Top")
		(15 "B.Paste" user "Package Geometry/Pastemask Bottom")
		(5 "F.SilkS" user "Ref Des/Silkscreen Top")
		(7 "B.SilkS" user "Ref Des/Silkscreen Bottom")
		(1 "F.Mask" user "Board Geometry/Soldermask Top")
		(3 "B.Mask" user "Board Geometry/Soldermask Bottom")
		(17 "Dwgs.User" user "User.Drawings")
		(19 "Cmts.User" user "User.Comments")
		(21 "Eco1.User" user "User.Eco1")
		(23 "Eco2.User" user "User.Eco2")
		(25 "Edge.Cuts" user "Board Geometry/Outline")
		(27 "Margin" user)
		(31 "F.CrtYd" user "Package Geometry/Place Bound Top")
		(29 "B.CrtYd" user "Package Geometry/Place Bound Bottom")
		(35 "F.Fab" user "Ref Des/Assembly Top")
		(33 "B.Fab" user "Ref Des/Assembly Bottom")
	)
	(footprint ""
		(layer "F.Cu")
		(at 166.1668 -428.5996 180)
		(property "Reference" "R3105"
			(at 0 0 180)
			(layer "F.SilkS")
			(hide yes)
			(effects
				(font
					(size 1.27 1.27)
				)
			)
		)
		(property "Value" ""
			(at 0 0 180)
			(layer "F.Fab")
			(effects
				(font
					(size 1.27 1.27)
				)
			)
		)
		(duplicate_pad_numbers_are_jumpers no)
		(fp_line
			(start 0.7874 0.4064)
			(end -0.7874 0.4064)
			(stroke
				(width 0.1524)
				(type default)
			)
			(layer "F.SilkS")
		)
		(fp_line
			(start 0.7874 -0.4064)
			(end 0.7874 0.4064)
			(stroke
				(width 0.1524)
				(type default)
			)
			(layer "F.SilkS")
		)
		(fp_line
			(start -0.7874 0.4064)
			(end -0.7874 -0.4064)
			(stroke
				(width 0.1524)
				(type default)
			)
			(layer "F.SilkS")
		)
		(fp_line
			(start -0.7874 -0.4064)
			(end 0.7874 -0.4064)
			(stroke
				(width 0.1524)
				(type default)
			)
			(layer "F.SilkS")
		)
		(fp_line
			(start 0.67945 0.3048)
			(end 0.120396 0.3048)
			(stroke
				(width 0.1)
				(type default)
			)
			(layer "F.Fab")
		)
		(fp_line
			(start 0.67945 -0.3048)
			(end 0.67945 0.3048)
			(stroke
				(width 0.1)
				(type default)
			)
			(layer "F.Fab")
		)
		(fp_line
			(start 0.12065 -0.2794)
			(end 0.12065 -0.3048)
			(stroke
				(width 0.1)
				(type default)
			)
			(layer "F.Fab")
		)
		(fp_line
			(start 0.12065 -0.3048)
			(end 0.67945 -0.3048)
			(stroke
				(width 0.1)
				(type default)
			)
			(layer "F.Fab")
		)
		(fp_line
			(start 0.120396 0.3048)
			(end 0.120396 0.2794)
			(stroke
				(width 0.1)
				(type default)
			)
			(layer "F.Fab")
		)
		(fp_line
			(start 0.120396 0.2794)
			(end -0.12065 0.2794)
			(stroke
				(width 0.1)
				(type default)
			)
			(layer "F.Fab")
		)
		(fp_line
			(start -0.12065 0.3048)
			(end -0.67945 0.3048)
			(stroke
				(width 0.1)
				(type default)
			)
			(layer "F.Fab")
		)
		(fp_line
			(start -0.12065 0.2794)
			(end -0.12065 0.3048)
			(stroke
				(width 0.1)
				(type default)
			)
			(layer "F.Fab")
		)
		(fp_line
			(start -0.12065 -0.2794)
			(end 0.12065 -0.2794)
			(stroke
				(width 0.1)
				(type default)
			)
			(layer "F.Fab")
		)
		(fp_line
			(start -0.12065 -0.305054)
			(end -0.12065 -0.2794)
			(stroke
				(width 0.1)
				(type default)
			)
			(layer "F.Fab")
		)
		(fp_line
			(start -0.67945 0.3048)
			(end -0.67945 -0.305054)
			(stroke
				(width 0.1)
				(type default)
			)
			(layer "F.Fab")
		)
		(fp_line
			(start -0.67945 -0.305054)
			(end -0.12065 -0.305054)
			(stroke
				(width 0.1)
				(type default)
			)
			(layer "F.Fab")
		)
		(pad "1" smd circle
			(at -0.40005 0 180)
			(size 0 0)
			(layers "F.Cu" "F.Mask" "F.Paste")
			(net "SMB_BMC_SWB_SCL")
		)
		(pad "2" smd circle
			(at 0.40005 0 180)
			(size 0 0)
			(layers "F.Cu" "F.Mask" "F.Paste")
			(net "SMB_BMC_SWB_R_SCL")
		)
	)
	(footprint ""
		(layer "F.Cu")
		(at 69.036438 -31.887922 90)
		(property "Reference" "PC2164"
			(at 0 0 90)
			(layer "F.SilkS")
			(hide yes)
			(effects
				(font
					(size 1.27 1.27)
				)
			)
		)
		(property "Value" ""
			(at 0 0 90)
			(layer "F.Fab")
			(effects
				(font
					(size 1.27 1.27)
				)
			)
		)
		(duplicate_pad_numbers_are_jumpers no)
		(fp_line
			(start 0.7874 -0.4064)
			(end 0.7874 0.4064)
			(stroke
				(width 0.1524)
				(type default)
			)
			(layer "F.SilkS")
		)
		(fp_line
			(start -0.7874 -0.4064)
			(end 0.7874 -0.4064)
			(stroke
				(width 0.1524)
				(type default)
			)
			(layer "F.SilkS")
		)
		(fp_line
			(start 0.7874 0.4064)
			(end -0.7874 0.4064)
			(stroke
				(width 0.1524)
				(type default)
			)
			(layer "F.SilkS")
		)
		(fp_line
			(start -0.7874 0.4064)
			(end -0.7874 -0.4064)
			(stroke
				(width 0.1524)
				(type default)
			)
			(layer "F.SilkS")
		)
		(fp_line
			(start -0.12065 -0.305054)
			(end -0.12065 -0.2794)
			(stroke
				(width 0.1)
				(type default)
			)
			(layer "F.Fab")
		)
		(fp_line
			(start -0.67945 -0.305054)
			(end -0.12065 -0.305054)
			(stroke
				(width 0.1)
				(type default)
			)
			(layer "F.Fab")
		)
		(fp_line
			(start 0.67945 -0.3048)
			(end 0.67945 0.3048)
			(stroke
				(width 0.1)
				(type default)
			)
			(layer "F.Fab")
		)
		(fp_line
			(start 0.12065 -0.3048)
			(end 0.67945 -0.3048)
			(stroke
				(width 0.1)
				(type default)
			)
			(layer "F.Fab")
		)
		(fp_line
			(start 0.12065 -0.2794)
			(end 0.12065 -0.3048)
			(stroke
				(width 0.1)
				(type default)
			)
			(layer "F.Fab")
		)
		(fp_line
			(start -0.12065 -0.2794)
			(end 0.12065 -0.2794)
			(stroke
				(width 0.1)
				(type default)
			)
			(layer "F.Fab")
		)
		(fp_line
			(start 0.120396 0.2794)
			(end -0.12065 0.2794)
			(stroke
				(width 0.1)
				(type default)
			)
			(layer "F.Fab")
		)
		(fp_line
			(start -0.12065 0.2794)
			(end -0.12065 0.3048)
			(stroke
				(width 0.1)
				(type default)
			)
			(layer "F.Fab")
		)
		(fp_line
			(start 0.67945 0.3048)
			(end 0.120396 0.3048)
			(stroke
				(width 0.1)
				(type default)
			)
			(layer "F.Fab")
		)
		(fp_line
			(start 0.120396 0.3048)
			(end 0.120396 0.2794)
			(stroke
				(width 0.1)
				(type default)
			)
			(layer "F.Fab")
		)
		(fp_line
			(start -0.12065 0.3048)
			(end -0.67945 0.3048)
			(stroke
				(width 0.1)
				(type default)
			)
			(layer "F.Fab")
		)
		(fp_line
			(start -0.67945 0.3048)
			(end -0.67945 -0.305054)
			(stroke
				(width 0.1)
				(type default)
			)
			(layer "F.Fab")
		)
		(pad "1" smd circle
			(at -0.40005 0 90)
			(size 0 0)
			(layers "F.Cu" "F.Mask" "F.Paste")
			(net "P12V_OCP_TIMER_2")
		)
		(pad "2" smd circle
			(at 0.40005 0 90)
			(size 0 0)
			(layers "F.Cu" "F.Mask" "F.Paste")
			(net "GND")
		)
	)
	(footprint ""
		(layer "F.Cu")
		(at 133.653022 -395.6304 -90)
		(property "Reference" "R6900"
			(at 0 0 270)
			(layer "F.SilkS")
			(hide yes)
			(effects
				(font
					(size 1.27 1.27)
				)
			)
		)
		(property "Value" ""
			(at 0 0 270)
			(layer "F.Fab")
			(effects
				(font
					(size 1.27 1.27)
				)
			)
		)
		(duplicate_pad_numbers_are_jumpers no)
		(fp_line
			(start -0.32512 0.175006)
			(end -0.32512 -0.175006)
			(stroke
				(width 0.1)
				(type default)
			)
			(layer "F.Fab")
		)
		(fp_line
			(start 0.32512 0.175006)
			(end -0.32512 0.175006)
			(stroke
				(width 0.1)
				(type default)
			)
			(layer "F.Fab")
		)
		(fp_line
			(start -0.32512 -0.175006)
			(end 0.32512 -0.175006)
			(stroke
				(width 0.1)
				(type default)
			)
			(layer "F.Fab")
		)
		(fp_line
			(start 0.32512 -0.175006)
			(end 0.32512 0.175006)
			(stroke
				(width 0.1)
				(type default)
			)
			(layer "F.Fab")
		)
		(pad "1" smd rect
			(at -0.2667 0 270)
			(size 0.3048 0.381)
			(layers "F.Cu" "F.Mask" "F.Paste")
			(net "P1V8_CPU1_RT_1D")
		)
		(pad "2" smd rect
			(at 0.2667 0 90)
			(size 0.3048 0.381)
			(layers "F.Cu" "F.Mask" "F.Paste")
			(net "RT_CPU1_P3_VQPS")
		)
	)
	(footprint ""
		(layer "F.Cu")
		(at 103.886 -423.164 -90)
		(property "Reference" "U255"
			(at 1.251712 -3.660902 90)
			(unlocked yes)
			(layer "F.SilkS")
			(effects
				(font
					(size 0.7874 0.5842)
					(thickness 0.1524)
				)
				(justify left)
			)
		)
		(property "Value" ""
			(at 0 0 270)
			(layer "F.Fab")
			(effects
				(font
					(size 1.27 1.27)
				)
			)
		)
		(duplicate_pad_numbers_are_jumpers no)
		(fp_line
			(start -1.38176 1.100074)
			(end 1.38176 1.100074)
			(stroke
				(width 0.1524)
				(type default)
			)
			(layer "F.SilkS")
		)
		(fp_line
			(start 1.38176 1.100074)
			(end 1.38176 -1.100074)
			(stroke
				(width 0.1524)
				(type default)
			)
			(layer "F.SilkS")
		)
		(fp_line
			(start 0 -0.508)
			(end -0.592074 -1.100074)
			(stroke
				(width 0.1524)
				(type default)
			)
			(layer "F.SilkS")
		)
		(fp_line
			(start -1.38176 -1.100074)
			(end -1.38176 1.100074)
			(stroke
				(width 0.1524)
				(type default)
			)
			(layer "F.SilkS")
		)
		(fp_line
			(start -0.592074 -1.100074)
			(end -1.38176 -1.100074)
			(stroke
				(width 0.1524)
				(type default)
			)
			(layer "F.SilkS")
		)
		(fp_line
			(start 0.592074 -1.100074)
			(end 0 -0.508)
			(stroke
				(width 0.1524)
				(type default)
			)
			(layer "F.SilkS")
		)
		(fp_line
			(start 1.38176 -1.100074)
			(end 0.592074 -1.100074)
			(stroke
				(width 0.1524)
				(type default)
			)
			(layer "F.SilkS")
		)
		(fp_poly
			(pts
				(xy -1.9431 -0.429768) (xy -1.9431 -0.870204) (xy -1.50241 -0.649986)
			)
			(stroke
				(width 0)
				(type default)
			)
			(fill yes)
			(layer "F.SilkS")
		)
		(fp_line
			(start -0.674878 1.100074)
			(end 0.674878 1.100074)
			(stroke
				(width 0.1)
				(type default)
			)
			(layer "F.Fab")
		)
		(fp_line
			(start 0.674878 1.100074)
			(end 0.674878 -1.100074)
			(stroke
				(width 0.1)
				(type default)
			)
			(layer "F.Fab")
		)
		(fp_line
			(start -0.674878 -1.100074)
			(end -0.674878 1.100074)
			(stroke
				(width 0.1)
				(type default)
			)
			(layer "F.Fab")
		)
		(fp_line
			(start 0.674878 -1.100074)
			(end -0.674878 -1.100074)
			(stroke
				(width 0.1)
				(type default)
			)
			(layer "F.Fab")
		)
		(fp_poly
			(pts
				(xy -1.9431 -0.870204) (xy -1.50241 -0.649986) (xy -1.9431 -0.429768)
			)
			(stroke
				(width 0)
				(type default)
			)
			(fill yes)
			(layer "F.Fab")
		)
		(pad "1" smd rect
			(at -0.94996 -0.649986 180)
			(size 0.4318 0.6096)
			(layers "F.Cu" "F.Mask" "F.Paste")
			(net "GPU_NVS_PWR_BRAKE_N")
		)
		(pad "2" smd rect
			(at -0.94996 0 180)
			(size 0.4318 0.6096)
			(layers "F.Cu" "F.Mask" "F.Paste")
			(net "GND")
		)
		(pad "3" smd rect
			(at -0.94996 0.649986 180)
			(size 0.4318 0.6096)
			(layers "F.Cu" "F.Mask" "F.Paste")
			(net "GPU_FPGA_EROT_RST_N")
		)
		(pad "4" smd rect
			(at 0.94996 0.649986 180)
			(size 0.4318 0.6096)
			(layers "F.Cu" "F.Mask" "F.Paste")
			(net "GPU_FPGA_EROT_RST_BUF_R_N")
		)
		(pad "5" smd rect
			(at 0.94996 0 180)
			(size 0.4318 0.6096)
			(layers "F.Cu" "F.Mask" "F.Paste")
			(net "P3V3_AUX")
		)
		(pad "6" smd rect
			(at 0.94996 -0.649986 180)
			(size 0.4318 0.6096)
			(layers "F.Cu" "F.Mask" "F.Paste")
			(net "GPU_NVS_PWR_BRAKE_N_R")
		)
	)
	(footprint ""
		(layer "F.Cu")
		(at 89.533984 -32.07131)
		(property "Reference" "U321"
			(at -2.2606 -2.352548 0)
			(unlocked yes)
			(layer "F.SilkS")
			(effects
				(font
					(size 0.7874 0.5842)
					(thickness 0.1524)
				)
				(justify left)
			)
		)
		(property "Value" ""
			(at 0 0 0)
			(layer "F.Fab")
			(effects
				(font
					(size 1.27 1.27)
				)
			)
		)
		(duplicate_pad_numbers_are_jumpers no)
		(fp_line
			(start -2.032 -1.549908)
			(end 2.032 -1.549908)
			(stroke
				(width 0.1524)
				(type default)
			)
			(layer "F.SilkS")
		)
		(fp_line
			(start -2.032 1.549908)
			(end -2.032 -1.549908)
			(stroke
				(width 0.1524)
				(type default)
			)
			(layer "F.SilkS")
		)
		(fp_line
			(start 2.032 -1.549908)
			(end 2.032 1.549908)
			(stroke
				(width 0.1524)
				(type default)
			)
			(layer "F.SilkS")
		)
		(fp_line
			(start 2.032 1.549908)
			(end -2.032 1.549908)
			(stroke
				(width 0.1524)
				(type default)
			)
			(layer "F.SilkS")
		)
		(fp_poly
			(pts
				(xy -2.733548 -2.327656) (xy -2.993644 -1.89103) (xy -2.208784 -1.71958)
			)
			(stroke
				(width 0)
				(type default)
			)
			(fill yes)
			(layer "F.SilkS")
		)
		(fp_line
			(start -0.849884 -1.549908)
			(end -0.849884 1.549908)
			(stroke
				(width 0.1)
				(type default)
			)
			(layer "F.Fab")
		)
		(fp_line
			(start -0.849884 1.549908)
			(end 0.849884 1.549908)
			(stroke
				(width 0.1)
				(type default)
			)
			(layer "F.Fab")
		)
		(fp_line
			(start 0.849884 -1.549908)
			(end -0.849884 -1.549908)
			(stroke
				(width 0.1)
				(type default)
			)
			(layer "F.Fab")
		)
		(fp_line
			(start 0.849884 1.549908)
			(end 0.849884 -1.549908)
			(stroke
				(width 0.1)
				(type default)
			)
			(layer "F.Fab")
		)
		(fp_poly
			(pts
				(xy -2.9464 -1.2192) (xy -2.9464 -0.7112) (xy -2.1844 -0.9652)
			)
			(stroke
				(width 0)
				(type default)
			)
			(fill yes)
			(layer "F.Fab")
		)
		(pad "1" smd rect
			(at -1.225042 -0.94996 270)
			(size 0.4572 1.3208)
			(layers "F.Cu" "F.Mask" "F.Paste")
			(net "CLK_50M_NCSI_OCP_V3_2")
		)
		(pad "2" smd rect
			(at -1.225042 0 270)
			(size 0.4572 1.3208)
			(layers "F.Cu" "F.Mask" "F.Paste")
			(net "CLK_50M_NCSI_OCP_V3_2_ISO_R")
		)
		(pad "3" smd rect
			(at -1.225042 0.94996 270)
			(size 0.4572 1.3208)
			(layers "F.Cu" "F.Mask" "F.Paste")
			(net "GND")
		)
		(pad "4" smd rect
			(at 1.225042 0.94996 270)
			(size 0.4572 1.3208)
			(layers "F.Cu" "F.Mask" "F.Paste")
			(net "FB_BMC_ISOLATE1")
		)
		(pad "5" smd rect
			(at 1.225042 -0.94996 270)
			(size 0.4572 1.3208)
			(layers "F.Cu" "F.Mask" "F.Paste")
			(net "P3V3_AUX")
		)
	)
	(footprint ""
		(layer "F.Cu")
		(at 218.011502 -72.015858 180)
		(property "Reference" "PR3971"
			(at 0 0 180)
			(layer "F.SilkS")
			(hide yes)
			(effects
				(font
					(size 1.27 1.27)
				)
			)
		)
		(property "Value" ""
			(at 0 0 180)
			(layer "F.Fab")
			(effects
				(font
					(size 1.27 1.27)
				)
			)
		)
		(duplicate_pad_numbers_are_jumpers no)
		(fp_line
			(start 0.7874 0.4064)
			(end -0.7874 0.4064)
			(stroke
				(width 0.1524)
				(type default)
			)
			(layer "F.SilkS")
		)
		(fp_line
			(start 0.7874 -0.4064)
			(end 0.7874 0.4064)
			(stroke
				(width 0.1524)
				(type default)
			)
			(layer "F.SilkS")
		)
		(fp_line
			(start -0.7874 0.4064)
			(end -0.7874 -0.4064)
			(stroke
				(width 0.1524)
				(type default)
			)
			(layer "F.SilkS")
		)
		(fp_line
			(start -0.7874 -0.4064)
			(end 0.7874 -0.4064)
			(stroke
				(width 0.1524)
				(type default)
			)
			(layer "F.SilkS")
		)
		(fp_line
			(start 0.67945 0.3048)
			(end 0.120396 0.3048)
			(stroke
				(width 0.1)
				(type default)
			)
			(layer "F.Fab")
		)
		(fp_line
			(start 0.67945 -0.3048)
			(end 0.67945 0.3048)
			(stroke
				(width 0.1)
				(type default)
			)
			(layer "F.Fab")
		)
		(fp_line
			(start 0.12065 -0.2794)
			(end 0.12065 -0.3048)
			(stroke
				(width 0.1)
				(type default)
			)
			(layer "F.Fab")
		)
		(fp_line
			(start 0.12065 -0.3048)
			(end 0.67945 -0.3048)
			(stroke
				(width 0.1)
				(type default)
			)
			(layer "F.Fab")
		)
		(fp_line
			(start 0.120396 0.3048)
			(end 0.120396 0.2794)
			(stroke
				(width 0.1)
				(type default)
			)
			(layer "F.Fab")
		)
		(fp_line
			(start 0.120396 0.2794)
			(end -0.12065 0.2794)
			(stroke
				(width 0.1)
				(type default)
			)
			(layer "F.Fab")
		)
		(fp_line
			(start -0.12065 0.3048)
			(end -0.67945 0.3048)
			(stroke
				(width 0.1)
				(type default)
			)
			(layer "F.Fab")
		)
		(fp_line
			(start -0.12065 0.2794)
			(end -0.12065 0.3048)
			(stroke
				(width 0.1)
				(type default)
			)
			(layer "F.Fab")
		)
		(fp_line
			(start -0.12065 -0.2794)
			(end 0.12065 -0.2794)
			(stroke
				(width 0.1)
				(type default)
			)
			(layer "F.Fab")
		)
		(fp_line
			(start -0.12065 -0.305054)
			(end -0.12065 -0.2794)
			(stroke
				(width 0.1)
				(type default)
			)
			(layer "F.Fab")
		)
		(fp_line
			(start -0.67945 0.3048)
			(end -0.67945 -0.305054)
			(stroke
				(width 0.1)
				(type default)
			)
			(layer "F.Fab")
		)
		(fp_line
			(start -0.67945 -0.305054)
			(end -0.12065 -0.305054)
			(stroke
				(width 0.1)
				(type default)
			)
			(layer "F.Fab")
		)
		(pad "1" smd circle
			(at -0.40005 0 180)
			(size 0 0)
			(layers "F.Cu" "F.Mask" "F.Paste")
			(net "P3V3_E1S_SENSE_0")
		)
		(pad "2" smd circle
			(at 0.40005 0 180)
			(size 0 0)
			(layers "F.Cu" "F.Mask" "F.Paste")
			(net "GND")
		)
	)
	(footprint ""
		(layer "F.Cu")
		(at 48.803306 19.444716 -90)
		(property "Reference" "JP6001_23"
			(at 0 0 270)
			(layer "F.SilkS")
			(hide yes)
			(effects
				(font
					(size 1.27 1.27)
				)
			)
		)
		(property "Value" ""
			(at 0 0 270)
			(layer "F.Fab")
			(effects
				(font
					(size 1.27 1.27)
				)
			)
		)
		(duplicate_pad_numbers_are_jumpers no)
		(pad "1" smd circle
			(at 0 0 270)
			(size 0.762 0.762)
			(layers "F.Cu" "F.Mask" "F.Paste")
			(net "Net_10791")
		)
	)
)
